# T6G (Grand Teton) — schematic netlist excerpt (pin names and nets, part order shuffled) for the footprints in the layout excerpt that follows; sources: Cadence DE-HDL packaged netlist, KiCad conversion of 04192023_DAF0TMB3IC0_F0TG_MB_C_brd_V02_OCP.brd

R587  Q_RES  1K 1% CHIP  pkg 0402LF  page 250 : A = PCA9548_PCIE3_ADDR0 ; B = GND
R1451  Q_RES  1K 1% CHIP  pkg 0201LF  page 185 : A = P1V8_CPU1_RT_1D ; B = SMB_RT_CPU1_P1_ROM_MUX_1D_SCL
PC6629  Q_CAPP  390UF 2.5V 20% ALUM  pkg SMLF  page 365 : A = P0V9_CPU1_RT_2D ; B = GND

(kicad_pcb
	(version 20260206)
	(generator "pcbnew")
	(generator_version "10.0")
	(general
		(thickness 1.6)
		(legacy_teardrops no)
	)
	(paper "A4")
	(title_block
		(title "04192023_DAF0TMB3IC0_F0TG_MB_C_brd_V02_OCP.brd")
		(comment 1 "Grand Teton / footprints 316-318 of 8354")
	)
	(layers
		(0 "F.Cu" signal "TOP")
		(4 "In1.Cu" signal "GND")
		(6 "In2.Cu" signal "IN1")
		(8 "In3.Cu" signal "GND1")
		(10 "In4.Cu" signal "IN2")
		(12 "In5.Cu" signal "GND2")
		(14 "In6.Cu" signal "IN3")
		(16 "In7.Cu" signal "GND3")
		(18 "In8.Cu" signal "VCC")
		(20 "In9.Cu" signal "VCC1")
		(22 "In10.Cu" signal "GND4")
		(24 "In11.Cu" signal "IN4")
		(26 "In12.Cu" signal "GND5")
		(28 "In13.Cu" signal "IN5")
		(30 "In14.Cu" signal "GND6")
		(32 "In15.Cu" signal "IN6")
		(34 "In16.Cu" signal "GND7")
		(2 "B.Cu" signal "BOTTOM")
		(9 "F.Adhes" user "F.Adhesive")
		(11 "B.Adhes" user "B.Adhesive")
		(13 "F.Paste" user "Package Geometry/Pastemask Top")
		(15 "B.Paste" user "Package Geometry/Pastemask Bottom")
		(5 "F.SilkS" user "Ref Des/Silkscreen Top")
		(7 "B.SilkS" user "Ref Des/Silkscreen Bottom")
		(1 "F.Mask" user "Board Geometry/Soldermask Top")
		(3 "B.Mask" user "Board Geometry/Soldermask Bottom")
		(17 "Dwgs.User" user "User.Drawings")
		(19 "Cmts.User" user "User.Comments")
		(21 "Eco1.User" user "User.Eco1")
		(23 "Eco2.User" user "User.Eco2")
		(25 "Edge.Cuts" user "Board Geometry/Outline")
		(27 "Margin" user)
		(31 "F.CrtYd" user "Package Geometry/Place Bound Top")
		(29 "B.CrtYd" user "Package Geometry/Place Bound Bottom")
		(35 "F.Fab" user "Ref Des/Assembly Top")
		(33 "B.Fab" user "Ref Des/Assembly Bottom")
	)
	(footprint ""
		(layer "F.Cu")
		(at 279.513792 -124.305314 180)
		(property "Reference" "R587"
			(at 0 0 180)
			(layer "F.SilkS")
			(hide yes)
			(effects
				(font
					(size 1.27 1.27)
				)
			)
		)
		(property "Value" ""
			(at 0 0 180)
			(layer "F.Fab")
			(effects
				(font
					(size 1.27 1.27)
				)
			)
		)
		(duplicate_pad_numbers_are_jumpers no)
		(fp_line
			(start 0.7874 0.4064)
			(end -0.7874 0.4064)
			(stroke
				(width 0.1524)
				(type default)
			)
			(layer "F.SilkS")
		)
		(fp_line
			(start 0.7874 -0.4064)
			(end 0.7874 0.4064)
			(stroke
				(width 0.1524)
				(type default)
			)
			(layer "F.SilkS")
		)
		(fp_line
			(start -0.7874 0.4064)
			(end -0.7874 -0.4064)
			(stroke
				(width 0.1524)
				(type default)
			)
			(layer "F.SilkS")
		)
		(fp_line
			(start -0.7874 -0.4064)
			(end 0.7874 -0.4064)
			(stroke
				(width 0.1524)
				(type default)
			)
			(layer "F.SilkS")
		)
		(fp_line
			(start 0.67945 0.3048)
			(end 0.120396 0.3048)
			(stroke
				(width 0.1)
				(type default)
			)
			(layer "F.Fab")
		)
		(fp_line
			(start 0.67945 -0.3048)
			(end 0.67945 0.3048)
			(stroke
				(width 0.1)
				(type default)
			)
			(layer "F.Fab")
		)
		(fp_line
			(start 0.12065 -0.2794)
			(end 0.12065 -0.3048)
			(stroke
				(width 0.1)
				(type default)
			)
			(layer "F.Fab")
		)
		(fp_line
			(start 0.12065 -0.3048)
			(end 0.67945 -0.3048)
			(stroke
				(width 0.1)
				(type default)
			)
			(layer "F.Fab")
		)
		(fp_line
			(start 0.120396 0.3048)
			(end 0.120396 0.2794)
			(stroke
				(width 0.1)
				(type default)
			)
			(layer "F.Fab")
		)
		(fp_line
			(start 0.120396 0.2794)
			(end -0.12065 0.2794)
			(stroke
				(width 0.1)
				(type default)
			)
			(layer "F.Fab")
		)
		(fp_line
			(start -0.12065 0.3048)
			(end -0.67945 0.3048)
			(stroke
				(width 0.1)
				(type default)
			)
			(layer "F.Fab")
		)
		(fp_line
			(start -0.12065 0.2794)
			(end -0.12065 0.3048)
			(stroke
				(width 0.1)
				(type default)
			)
			(layer "F.Fab")
		)
		(fp_line
			(start -0.12065 -0.2794)
			(end 0.12065 -0.2794)
			(stroke
				(width 0.1)
				(type default)
			)
			(layer "F.Fab")
		)
		(fp_line
			(start -0.12065 -0.305054)
			(end -0.12065 -0.2794)
			(stroke
				(width 0.1)
				(type default)
			)
			(layer "F.Fab")
		)
		(fp_line
			(start -0.67945 0.3048)
			(end -0.67945 -0.305054)
			(stroke
				(width 0.1)
				(type default)
			)
			(layer "F.Fab")
		)
		(fp_line
			(start -0.67945 -0.305054)
			(end -0.12065 -0.305054)
			(stroke
				(width 0.1)
				(type default)
			)
			(layer "F.Fab")
		)
		(pad "1" smd circle
			(at -0.40005 0 180)
			(size 0 0)
			(layers "F.Cu" "F.Mask" "F.Paste")
			(net "PCA9548_PCIE3_ADDR0")
		)
		(pad "2" smd circle
			(at 0.40005 0 180)
			(size 0 0)
			(layers "F.Cu" "F.Mask" "F.Paste")
			(net "GND")
		)
	)
	(footprint ""
		(layer "F.Cu")
		(at 12.769088 -373.44985 -90)
		(property "Reference" "PC6629"
			(at 4.41452 2.355088 0)
			(unlocked yes)
			(layer "F.SilkS")
			(effects
				(font
					(size 0.7874 0.5842)
					(thickness 0.1524)
				)
				(justify left)
			)
		)
		(property "Value" ""
			(at 0 0 270)
			(layer "F.Fab")
			(effects
				(font
					(size 1.27 1.27)
				)
			)
		)
		(duplicate_pad_numbers_are_jumpers no)
		(fp_line
			(start -1.988058 2.750058)
			(end 2.750058 2.750058)
			(stroke
				(width 0.1524)
				(type default)
			)
			(layer "F.SilkS")
		)
		(fp_line
			(start 2.750058 2.750058)
			(end 2.750058 0.9398)
			(stroke
				(width 0.1524)
				(type default)
			)
			(layer "F.SilkS")
		)
		(fp_line
			(start -2.750058 1.988058)
			(end -1.988058 2.750058)
			(stroke
				(width 0.1524)
				(type default)
			)
			(layer "F.SilkS")
		)
		(fp_line
			(start -2.750058 0.9398)
			(end -2.750058 1.988058)
			(stroke
				(width 0.1524)
				(type default)
			)
			(layer "F.SilkS")
		)
		(fp_line
			(start 2.750058 -0.9398)
			(end 2.750058 -2.750058)
			(stroke
				(width 0.1524)
				(type default)
			)
			(layer "F.SilkS")
		)
		(fp_line
			(start -2.750058 -1.988058)
			(end -2.750058 -0.9398)
			(stroke
				(width 0.1524)
				(type default)
			)
			(layer "F.SilkS")
		)
		(fp_line
			(start -1.988058 -2.750058)
			(end -2.750058 -1.988058)
			(stroke
				(width 0.1524)
				(type default)
			)
			(layer "F.SilkS")
		)
		(fp_line
			(start 2.750058 -2.750058)
			(end -1.988058 -2.750058)
			(stroke
				(width 0.1524)
				(type default)
			)
			(layer "F.SilkS")
		)
		(fp_line
			(start -2.750058 2.750058)
			(end 2.750058 2.750058)
			(stroke
				(width 0.1)
				(type default)
			)
			(layer "F.Fab")
		)
		(fp_line
			(start 2.750058 2.750058)
			(end 2.750058 -2.750058)
			(stroke
				(width 0.1)
				(type default)
			)
			(layer "F.Fab")
		)
		(fp_line
			(start -2.750058 -2.750058)
			(end -2.750058 2.750058)
			(stroke
				(width 0.1)
				(type default)
			)
			(layer "F.Fab")
		)
		(fp_line
			(start 2.750058 -2.750058)
			(end -2.750058 -2.750058)
			(stroke
				(width 0.1)
				(type default)
			)
			(layer "F.Fab")
		)
		(pad "1" smd rect
			(at -2.199894 0)
			(size 1.6002 3.0226)
			(layers "F.Cu" "F.Mask" "F.Paste")
			(net "P0V9_CPU1_RT_2D")
		)
		(pad "2" smd rect
			(at 2.199894 0)
			(size 1.6002 3.0226)
			(layers "F.Cu" "F.Mask" "F.Paste")
			(net "GND")
		)
	)
	(footprint ""
		(layer "F.Cu")
		(at 118.11 -400.3548)
		(property "Reference" "R1451"
			(at 0 0 0)
			(layer "F.SilkS")
			(hide yes)
			(effects
				(font
					(size 1.27 1.27)
				)
			)
		)
		(property "Value" ""
			(at 0 0 0)
			(layer "F.Fab")
			(effects
				(font
					(size 1.27 1.27)
				)
			)
		)
		(duplicate_pad_numbers_are_jumpers no)
		(fp_line
			(start -0.32512 -0.175006)
			(end 0.32512 -0.175006)
			(stroke
				(width 0.1)
				(type default)
			)
			(layer "F.Fab")
		)
		(fp_line
			(start -0.32512 0.175006)
			(end -0.32512 -0.175006)
			(stroke
				(width 0.1)
				(type default)
			)
			(layer "F.Fab")
		)
		(fp_line
			(start 0.32512 -0.175006)
			(end 0.32512 0.175006)
			(stroke
				(width 0.1)
				(type default)
			)
			(layer "F.Fab")
		)
		(fp_line
			(start 0.32512 0.175006)
			(end -0.32512 0.175006)
			(stroke
				(width 0.1)
				(type default)
			)
			(layer "F.Fab")
		)
		(pad "1" smd rect
			(at -0.2667 0)
			(size 0.3048 0.381)
			(layers "F.Cu" "F.Mask" "F.Paste")
			(net "P1V8_CPU1_RT_1D")
		)
		(pad "2" smd rect
			(at 0.2667 0 180)
			(size 0.3048 0.381)
			(layers "F.Cu" "F.Mask" "F.Paste")
			(net "SMB_RT_CPU1_P1_ROM_MUX_1D_SCL")
		)
	)
)
